# TIMECARD (Time Appliance Project (Time Card)) — schematic netlist excerpt (pin names and nets, part order shuffled) for the footprints in the layout excerpt that follows; sources: Cadence DE-HDL packaged netlist, KiCad conversion of R4006-B0001-02_R01.brd

C278  CAPACITOR  0.1UF 25V 10%  pkg SMC_0402R_H022  page 19 : \1\ = XP1R8V_ICP10100 ; \2\ = SG
R412  RESISTOR  4.7KOHM 1%  pkg SMC_0402R_H016  page 17 : \1\ = XP3R3V_FPGA ; \2\ = UNNAMED_6_LM75BDPTSSOP8_I59_A1
SP47  NULL  pkg DUMMY  page 34

(kicad_pcb
	(version 20260206)
	(generator "pcbnew")
	(generator_version "10.0")
	(general
		(thickness 1.6)
		(legacy_teardrops no)
	)
	(paper "A4")
	(title_block
		(title "timecard-production-celestica-r4006 — R4006-B0001-02_R01.brd")
		(comment 1 "Time Appliance Project (Time Card) / footprints 642-644 of 1113")
	)
	(layers
		(0 "F.Cu" signal "TOP")
		(4 "In1.Cu" signal "L02_GND1")
		(6 "In2.Cu" signal "L03_SIG1")
		(8 "In3.Cu" signal "L04_GND2")
		(10 "In4.Cu" signal "L05_VCC1")
		(12 "In5.Cu" signal "L06_VCC2")
		(14 "In6.Cu" signal "L07_GND3")
		(16 "In7.Cu" signal "L08_SIG2")
		(18 "In8.Cu" signal "L09_GND4")
		(2 "B.Cu" signal "BOTTOM")
		(9 "F.Adhes" user "F.Adhesive")
		(11 "B.Adhes" user "B.Adhesive")
		(13 "F.Paste" user "Package Geometry/Pastemask Top")
		(15 "B.Paste" user "Package Geometry/Pastemask Bottom")
		(5 "F.SilkS" user "Ref Des/Silkscreen Top")
		(7 "B.SilkS" user "Ref Des/Silkscreen Bottom")
		(1 "F.Mask" user "Board Geometry/Soldermask Top")
		(3 "B.Mask" user "Board Geometry/Soldermask Bottom")
		(17 "Dwgs.User" user "User.Drawings")
		(19 "Cmts.User" user "User.Comments")
		(21 "Eco1.User" user "User.Eco1")
		(23 "Eco2.User" user "User.Eco2")
		(25 "Edge.Cuts" user "Board Geometry/Outline")
		(27 "Margin" user)
		(31 "F.CrtYd" user "Package Geometry/Place Bound Top")
		(29 "B.CrtYd" user "Package Geometry/Place Bound Bottom")
		(35 "F.Fab" user "Ref Des/Assembly Top")
		(33 "B.Fab" user "Ref Des/Assembly Bottom")
	)
	(footprint ""
		(layer "F.Cu")
		(at 23.608792 -68.1482)
		(property "Reference" "C278"
			(at 3.315208 -0.01143 0)
			(unlocked yes)
			(layer "F.SilkS")
			(effects
				(font
					(size 0.7874 0.5842)
					(thickness 0.1524)
				)
			)
		)
		(property "Value" "VAL*"
			(at 0.0762 2.067306 0)
			(unlocked yes)
			(layer "F.Fab")
			(hide yes)
			(effects
				(font
					(size 0.7874 0.5842)
					(thickness 0.1524)
				)
			)
		)
		(property "Tolerance" "TOL*"
			(at 0.0762 3.032506 0)
			(unlocked yes)
			(layer "Cmts.User")
			(hide yes)
			(effects
				(font
					(size 0.7874 0.5842)
					(thickness 0.1524)
				)
			)
		)
		(property "User Part Number" "PARTNUM*"
			(at 0.1016 4.023106 0)
			(unlocked yes)
			(layer "Cmts.User")
			(hide yes)
			(effects
				(font
					(size 0.7874 0.5842)
					(thickness 0.1524)
				)
			)
		)
		(property "Device Type" "CAPACITOR-G105-0B104-EK,0.1UF,A"
			(at 0.0508 1.127506 0)
			(unlocked yes)
			(layer "F.Fab")
			(hide yes)
			(effects
				(font
					(size 0.7874 0.5842)
					(thickness 0.1524)
				)
			)
		)
		(duplicate_pad_numbers_are_jumpers no)
		(fp_line
			(start -1.143 -0.5588)
			(end -1.143 0.5588)
			(stroke
				(width 0.1)
				(type default)
			)
			(layer "F.SilkS")
		)
		(fp_line
			(start -1.143 0.5588)
			(end 1.143 0.5588)
			(stroke
				(width 0.1)
				(type default)
			)
			(layer "F.SilkS")
		)
		(fp_line
			(start 1.143 -0.5588)
			(end -1.143 -0.5588)
			(stroke
				(width 0.1)
				(type default)
			)
			(layer "F.SilkS")
		)
		(fp_line
			(start 1.143 0.5588)
			(end 1.143 -0.5588)
			(stroke
				(width 0.1)
				(type default)
			)
			(layer "F.SilkS")
		)
		(fp_rect
			(start -1.143 -0.5588)
			(end 1.143 0.5588)
			(stroke
				(width 0)
				(type default)
			)
			(fill no)
			(layer "F.CrtYd")
		)
		(fp_line
			(start -0.508 -0.3048)
			(end -0.508 0.3048)
			(stroke
				(width 0.1)
				(type default)
			)
			(layer "F.Fab")
		)
		(fp_line
			(start -0.508 0.3048)
			(end 0.508 0.3048)
			(stroke
				(width 0.1)
				(type default)
			)
			(layer "F.Fab")
		)
		(fp_line
			(start 0.508 -0.3048)
			(end -0.508 -0.3048)
			(stroke
				(width 0.1)
				(type default)
			)
			(layer "F.Fab")
		)
		(fp_line
			(start 0.508 0.3048)
			(end 0.508 -0.3048)
			(stroke
				(width 0.1)
				(type default)
			)
			(layer "F.Fab")
		)
		(pad "1" smd rect
			(at -0.5334 0)
			(size 0.7112 0.6096)
			(layers "F.Cu" "F.Mask" "F.Paste")
			(net "XP1R8V_ICP10100")
		)
		(pad "2" smd rect
			(at 0.5334 0)
			(size 0.7112 0.6096)
			(layers "F.Cu" "F.Mask" "F.Paste")
			(net "SG")
		)
		(zone
			(layer "F.Cu")
			(hatch none 0.5)
			(connect_pads
				(clearance 0)
			)
			(min_thickness 0.25)
			(keepout
				(tracks allowed)
				(vias not_allowed)
				(pads allowed)
				(copperpour not_allowed)
				(footprints allowed)
			)
			(placement
				(enabled no)
				(sheetname "")
			)
			(fill
				(thermal_gap 0.5)
				(thermal_bridge_width 0.5)
				(island_removal_mode 0)
			)
			(polygon
				(pts
					(xy 23.532592 -68.453) (xy 23.532592 -67.8434) (xy 23.684992 -67.8434) (xy 23.684992 -68.453)
				)
			)
		)
	)
	(footprint ""
		(layer "F.Cu")
		(at 63.881 -135.509)
		(property "Reference" "SP47"
			(at 0 0 0)
			(layer "F.SilkS")
			(hide yes)
			(effects
				(font
					(size 1.27 1.27)
				)
			)
		)
		(property "Value" ""
			(at 0 0 0)
			(layer "F.Fab")
			(effects
				(font
					(size 1.27 1.27)
				)
			)
		)
		(duplicate_pad_numbers_are_jumpers no)
	)
	(footprint ""
		(layer "F.Cu")
		(at 54.0512 -74.9808 90)
		(property "Reference" "R412"
			(at -0.5588 4.40817 90)
			(unlocked yes)
			(layer "F.SilkS")
			(effects
				(font
					(size 0.7874 0.5842)
					(thickness 0.1524)
				)
			)
		)
		(property "Value" "VAL*"
			(at 0.02032 2.13233 90)
			(unlocked yes)
			(layer "F.Fab")
			(hide yes)
			(effects
				(font
					(size 0.7874 0.5842)
					(thickness 0.1524)
				)
			)
		)
		(property "Device Type" "RESISTOR-G155-14701-01,4.7KOHMA"
			(at 0.008382 1.210564 90)
			(unlocked yes)
			(layer "F.Fab")
			(hide yes)
			(effects
				(font
					(size 0.7874 0.5842)
					(thickness 0.1524)
				)
			)
		)
		(property "User Part Number" "PARTNUM*"
			(at 0.02032 4.024884 90)
			(unlocked yes)
			(layer "Cmts.User")
			(hide yes)
			(effects
				(font
					(size 0.7874 0.5842)
					(thickness 0.1524)
				)
			)
		)
		(property "Tolerance" "TOL*"
			(at 0.044704 3.05435 90)
			(unlocked yes)
			(layer "Cmts.User")
			(hide yes)
			(effects
				(font
					(size 0.7874 0.5842)
					(thickness 0.1524)
				)
			)
		)
		(duplicate_pad_numbers_are_jumpers no)
		(fp_line
			(start 1.143 -0.5588)
			(end -1.143 -0.5588)
			(stroke
				(width 0.1)
				(type default)
			)
			(layer "F.SilkS")
		)
		(fp_line
			(start -1.143 -0.5588)
			(end -1.143 0.5588)
			(stroke
				(width 0.1)
				(type default)
			)
			(layer "F.SilkS")
		)
		(fp_line
			(start 1.143 0.5588)
			(end 1.143 -0.5588)
			(stroke
				(width 0.1)
				(type default)
			)
			(layer "F.SilkS")
		)
		(fp_line
			(start -1.143 0.5588)
			(end 1.143 0.5588)
			(stroke
				(width 0.1)
				(type default)
			)
			(layer "F.SilkS")
		)
		(fp_rect
			(start -1.143 0.5588)
			(end 1.143 -0.5588)
			(stroke
				(width 0)
				(type default)
			)
			(fill no)
			(layer "F.CrtYd")
		)
		(fp_line
			(start 0.508 -0.3048)
			(end -0.508 -0.3048)
			(stroke
				(width 0.1)
				(type default)
			)
			(layer "F.Fab")
		)
		(fp_line
			(start -0.508 -0.3048)
			(end -0.508 0.3048)
			(stroke
				(width 0.1)
				(type default)
			)
			(layer "F.Fab")
		)
		(fp_line
			(start 0.508 0.3048)
			(end 0.508 -0.3048)
			(stroke
				(width 0.1)
				(type default)
			)
			(layer "F.Fab")
		)
		(fp_line
			(start -0.508 0.3048)
			(end 0.508 0.3048)
			(stroke
				(width 0.1)
				(type default)
			)
			(layer "F.Fab")
		)
		(pad "1" smd rect
			(at -0.5334 0 90)
			(size 0.7112 0.6096)
			(layers "F.Cu" "F.Mask" "F.Paste")
			(net "XP3R3V_FPGA")
		)
		(pad "2" smd rect
			(at 0.5334 0 90)
			(size 0.7112 0.6096)
			(layers "F.Cu" "F.Mask" "F.Paste")
			(net "UNNAMED_6_LM75BDPTSSOP8_I59_A1")
		)
		(zone
			(layer "F.Cu")
			(hatch none 0.5)
			(connect_pads
				(clearance 0)
			)
			(min_thickness 0.25)
			(keepout
				(tracks not_allowed)
				(vias allowed)
				(pads allowed)
				(copperpour not_allowed)
				(footprints allowed)
			)
			(placement
				(enabled no)
				(sheetname "")
			)
			(fill
				(thermal_gap 0.5)
				(thermal_bridge_width 0.5)
				(island_removal_mode 0)
			)
			(polygon
				(pts
					(xy 54.356 -74.9046) (xy 54.356 -75.057) (xy 53.7464 -75.057) (xy 53.7464 -74.9046)
				)
			)
		)
		(zone
			(layer "F.Cu")
			(hatch none 0.5)
			(connect_pads
				(clearance 0)
			)
			(min_thickness 0.25)
			(keepout
				(tracks allowed)
				(vias not_allowed)
				(pads allowed)
				(copperpour not_allowed)
				(footprints allowed)
			)
			(placement
				(enabled no)
				(sheetname "")
			)
			(fill
				(thermal_gap 0.5)
				(thermal_bridge_width 0.5)
				(island_removal_mode 0)
			)
			(polygon
				(pts
					(xy 54.356 -74.9046) (xy 54.356 -75.057) (xy 53.7464 -75.057) (xy 53.7464 -74.9046)
				)
			)
		)
	)
)
